# BASEBOARD_FAB2 (Tioga Pass) — schematic netlist excerpt (pin names and nets, part order shuffled) for the footprints in the layout excerpt that follows; sources: Cadence DE-HDL packaged netlist, KiCad conversion of Wiwynn_Tioga_Pass_MB.brd

C8E18  CAP_A  0.1UF 16V 10% X7R  pkg 0402V  page 154 : A = P3V3_STBY ; B = GND

EU8B1  SLG55021  IC  pkg SM  page 198
  VCC  = P5V_STBY
  \on\  = FM_CTNR_PS_ON
  SHDN_N  = P5V_STBY
  GND  = GND
  D  = P5V_STBY
  S  = P5V
  G  = P5V_SWITCH_G
  PG  = TP_SLG55021_P5V_8
  THPAD  = GND

C5G2  CAP_A  47UF 4V 20% X5R  pkg 0603V  page 217 : A = PVDDQ_ABC ; B = GND

(kicad_pcb
	(version 20260206)
	(generator "pcbnew")
	(generator_version "10.0")
	(general
		(thickness 1.6)
		(legacy_teardrops no)
	)
	(paper "A4")
	(title_block
		(title "Wiwynn_Tioga_Pass_MB.brd")
		(comment 1 "Tioga Pass / footprints 237-239 of 4770")
	)
	(layers
		(0 "F.Cu" signal "TOP")
		(4 "In1.Cu" signal "L2GND")
		(6 "In2.Cu" signal "L3")
		(8 "In3.Cu" signal "L4GND")
		(10 "In4.Cu" signal "L5")
		(12 "In5.Cu" signal "L6GND")
		(14 "In6.Cu" signal "L7VCC")
		(16 "In7.Cu" signal "L8VCC")
		(18 "In8.Cu" signal "L9GND")
		(20 "In9.Cu" signal "L10")
		(22 "In10.Cu" signal "L11GND")
		(24 "In11.Cu" signal "L12")
		(26 "In12.Cu" signal "L13GND")
		(2 "B.Cu" signal "BOTTOM")
		(9 "F.Adhes" user "F.Adhesive")
		(11 "B.Adhes" user "B.Adhesive")
		(13 "F.Paste" user "Package Geometry/Pastemask Top")
		(15 "B.Paste" user "Package Geometry/Pastemask Bottom")
		(5 "F.SilkS" user "Ref Des/Silkscreen Top")
		(7 "B.SilkS" user "Ref Des/Silkscreen Bottom")
		(1 "F.Mask" user "Board Geometry/Soldermask Top")
		(3 "B.Mask" user "Board Geometry/Soldermask Bottom")
		(17 "Dwgs.User" user "User.Drawings")
		(19 "Cmts.User" user "User.Comments")
		(21 "Eco1.User" user "User.Eco1")
		(23 "Eco2.User" user "User.Eco2")
		(25 "Edge.Cuts" user "Board Geometry/Outline")
		(27 "Margin" user)
		(31 "F.CrtYd" user "Package Geometry/Place Bound Top")
		(29 "B.CrtYd" user "Package Geometry/Place Bound Bottom")
		(35 "F.Fab" user "Ref Des/Assembly Top")
		(33 "B.Fab" user "Ref Des/Assembly Bottom")
	)
	(footprint ""
		(layer "F.Cu")
		(at 435.49062 -131.3053 -90)
		(property "Reference" "EU8B1"
			(at 3.04419 3.01244 0)
			(unlocked yes)
			(layer "F.SilkS")
			(effects
				(font
					(size 0.7874 0.5842)
					(thickness 0.1524)
				)
				(justify left)
			)
		)
		(property "Value" ""
			(at 0 0 270)
			(layer "F.Fab")
			(effects
				(font
					(size 1.27 1.27)
				)
			)
		)
		(duplicate_pad_numbers_are_jumpers no)
		(fp_circle
			(center -0.702056 -0.595376)
			(end -0.702056 -0.722376)
			(stroke
				(width 0.254)
				(type default)
			)
			(fill no)
			(layer "F.SilkS")
		)
		(fp_rect
			(start 0.5842 1.549908)
			(end 1.4732 -0.050292)
			(stroke
				(width 0)
				(type default)
			)
			(fill yes)
			(layer "F.Paste")
		)
		(fp_poly
			(pts
				(xy -0.021336 1.799844) (xy 2.078736 1.799844) (xy 2.078736 -0.300228) (xy -0.021336 -0.300228)
			)
			(stroke
				(width 0)
				(type default)
			)
			(fill no)
			(layer "F.CrtYd")
		)
		(fp_line
			(start -0.021336 1.799844)
			(end -0.021336 -0.300228)
			(stroke
				(width 0.1)
				(type default)
			)
			(layer "F.Fab")
		)
		(fp_line
			(start 2.078736 1.799844)
			(end -0.021336 1.799844)
			(stroke
				(width 0.1)
				(type default)
			)
			(layer "F.Fab")
		)
		(fp_line
			(start -0.021336 -0.300228)
			(end 2.078736 -0.300228)
			(stroke
				(width 0.1)
				(type default)
			)
			(layer "F.Fab")
		)
		(fp_line
			(start 2.078736 -0.300228)
			(end 2.078736 1.799844)
			(stroke
				(width 0.1)
				(type default)
			)
			(layer "F.Fab")
		)
		(fp_circle
			(center -0.702056 -0.595376)
			(end -0.702056 -0.722376)
			(stroke
				(width 0.254)
				(type default)
			)
			(fill no)
			(layer "F.Fab")
		)
		(pad "1" smd rect
			(at 0 0 270)
			(size 0.6604 0.3048)
			(layers "F.Cu" "F.Mask" "F.Paste")
			(net "P5V_STBY")
		)
		(pad "2" smd rect
			(at 0 0.499872 270)
			(size 0.6604 0.3048)
			(layers "F.Cu" "F.Mask" "F.Paste")
			(net "FM_CTNR_PS_ON")
		)
		(pad "3" smd rect
			(at 0 0.999744 270)
			(size 0.6604 0.3048)
			(layers "F.Cu" "F.Mask" "F.Paste")
			(net "P5V_STBY")
		)
		(pad "4" smd rect
			(at 0 1.499616 270)
			(size 0.6604 0.3048)
			(layers "F.Cu" "F.Mask" "F.Paste")
			(net "GND")
		)
		(pad "5" smd rect
			(at 2.0574 1.499616 270)
			(size 0.6604 0.3048)
			(layers "F.Cu" "F.Mask" "F.Paste")
			(net "P5V_STBY")
		)
		(pad "6" smd rect
			(at 2.0574 0.999744 270)
			(size 0.6604 0.3048)
			(layers "F.Cu" "F.Mask" "F.Paste")
			(net "P5V")
		)
		(pad "7" smd rect
			(at 2.0574 0.499872 270)
			(size 0.6604 0.3048)
			(layers "F.Cu" "F.Mask" "F.Paste")
			(net "P5V_SWITCH_G")
		)
		(pad "8" smd rect
			(at 2.0574 0 270)
			(size 0.6604 0.3048)
			(layers "F.Cu" "F.Mask" "F.Paste")
			(net "TP_SLG55021_P5V_8")
		)
		(pad "9" smd rect
			(at 1.0287 0.749808 270)
			(size 0.889 1.6002)
			(layers "F.Cu" "F.Mask" "F.Paste")
			(net "GND")
		)
	)
	(footprint ""
		(layer "F.Cu")
		(at 378.218192 -54.643528 90)
		(property "Reference" "C8E18"
			(at 0 0 90)
			(layer "F.SilkS")
			(hide yes)
			(effects
				(font
					(size 1.27 1.27)
				)
			)
		)
		(property "Value" ""
			(at 0 0 90)
			(layer "F.Fab")
			(effects
				(font
					(size 1.27 1.27)
				)
			)
		)
		(duplicate_pad_numbers_are_jumpers no)
		(fp_poly
			(pts
				(xy 0.3048 -0.1016) (xy 0.3048 0.9906) (xy -0.3048 0.9906) (xy -0.3048 -0.1016)
			)
			(stroke
				(width 0)
				(type default)
			)
			(fill no)
			(layer "F.CrtYd")
		)
		(fp_line
			(start 0.3048 -0.1016)
			(end -0.3048 -0.1016)
			(stroke
				(width 0.1)
				(type default)
			)
			(layer "F.Fab")
		)
		(fp_line
			(start -0.3048 -0.1016)
			(end -0.3048 0.9906)
			(stroke
				(width 0.1)
				(type default)
			)
			(layer "F.Fab")
		)
		(fp_line
			(start 0.3048 0.9906)
			(end 0.3048 -0.1016)
			(stroke
				(width 0.1)
				(type default)
			)
			(layer "F.Fab")
		)
		(fp_line
			(start -0.3048 0.9906)
			(end 0.3048 0.9906)
			(stroke
				(width 0.1)
				(type default)
			)
			(layer "F.Fab")
		)
		(pad "1" smd rect
			(at 0 0 90)
			(size 0.508 0.508)
			(layers "F.Cu" "F.Mask" "F.Paste")
			(net "P3V3_STBY")
		)
		(pad "2" smd rect
			(at 0 0.889 90)
			(size 0.508 0.508)
			(layers "F.Cu" "F.Mask" "F.Paste")
			(net "GND")
		)
		(zone
			(layer "F.Cu")
			(hatch none 0.5)
			(connect_pads
				(clearance 0)
			)
			(min_thickness 0.25)
			(keepout
				(tracks allowed)
				(vias not_allowed)
				(pads allowed)
				(copperpour not_allowed)
				(footprints allowed)
			)
			(placement
				(enabled no)
				(sheetname "")
			)
			(fill
				(thermal_gap 0.5)
				(thermal_bridge_width 0.5)
				(island_removal_mode 0)
			)
			(polygon
				(pts
					(xy 378.472192 -54.389528) (xy 378.472192 -54.897528) (xy 378.853192 -54.897528) (xy 378.853192 -54.389528)
				)
			)
		)
		(zone
			(layer "F.Cu")
			(hatch none 0.5)
			(connect_pads
				(clearance 0)
			)
			(min_thickness 0.25)
			(keepout
				(tracks not_allowed)
				(vias allowed)
				(pads allowed)
				(copperpour not_allowed)
				(footprints allowed)
			)
			(placement
				(enabled no)
				(sheetname "")
			)
			(fill
				(thermal_gap 0.5)
				(thermal_bridge_width 0.5)
				(island_removal_mode 0)
			)
			(polygon
				(pts
					(xy 378.853192 -54.389528) (xy 378.853192 -54.897528) (xy 378.472192 -54.897528) (xy 378.472192 -54.389528)
				)
			)
		)
	)
	(footprint ""
		(layer "F.Cu")
		(at 248.8565 -12.954 -90)
		(property "Reference" "C5G2"
			(at 1.848866 0.752348 270)
			(unlocked yes)
			(layer "F.SilkS")
			(effects
				(font
					(size 1.27 0.9652)
					(thickness 0.1524)
				)
			)
		)
		(property "Value" ""
			(at 0 0 270)
			(layer "F.Fab")
			(effects
				(font
					(size 1.27 1.27)
				)
			)
		)
		(duplicate_pad_numbers_are_jumpers no)
		(fp_rect
			(start -0.500126 1.598422)
			(end 0.500126 -0.201422)
			(stroke
				(width 0)
				(type default)
			)
			(fill no)
			(layer "F.CrtYd")
		)
		(fp_line
			(start -0.500126 1.598422)
			(end -0.500126 -0.201422)
			(stroke
				(width 0.1)
				(type default)
			)
			(layer "F.Fab")
		)
		(fp_line
			(start 0.500126 1.598422)
			(end -0.500126 1.598422)
			(stroke
				(width 0.1)
				(type default)
			)
			(layer "F.Fab")
		)
		(fp_line
			(start -0.500126 -0.201422)
			(end 0.500126 -0.201422)
			(stroke
				(width 0.1)
				(type default)
			)
			(layer "F.Fab")
		)
		(fp_line
			(start 0.500126 -0.201422)
			(end 0.500126 1.598422)
			(stroke
				(width 0.1)
				(type default)
			)
			(layer "F.Fab")
		)
		(pad "1" smd rect
			(at 0 0 180)
			(size 0.889 0.9906)
			(layers "F.Cu" "F.Mask" "F.Paste")
			(net "PVDDQ_ABC")
		)
		(pad "2" smd rect
			(at 0 1.397 180)
			(size 0.889 0.9906)
			(layers "F.Cu" "F.Mask" "F.Paste")
			(net "GND")
		)
		(zone
			(layer "F.Cu")
			(hatch none 0.5)
			(connect_pads
				(clearance 0)
			)
			(min_thickness 0.25)
			(keepout
				(tracks not_allowed)
				(vias allowed)
				(pads allowed)
				(copperpour not_allowed)
				(footprints allowed)
			)
			(placement
				(enabled no)
				(sheetname "")
			)
			(fill
				(thermal_gap 0.5)
				(thermal_bridge_width 0.5)
				(island_removal_mode 0)
			)
			(polygon
				(pts
					(xy 247.904 -13.4493) (xy 247.904 -12.4587) (xy 248.412 -12.4587) (xy 248.412 -13.4493)
				)
			)
		)
		(zone
			(layer "F.Cu")
			(hatch none 0.5)
			(connect_pads
				(clearance 0)
			)
			(min_thickness 0.25)
			(keepout
				(tracks allowed)
				(vias not_allowed)
				(pads allowed)
				(copperpour not_allowed)
				(footprints allowed)
			)
			(placement
				(enabled no)
				(sheetname "")
			)
			(fill
				(thermal_gap 0.5)
				(thermal_bridge_width 0.5)
				(island_removal_mode 0)
			)
			(polygon
				(pts
					(xy 247.904 -13.4493) (xy 247.904 -12.4587) (xy 248.412 -12.4587) (xy 248.412 -13.4493)
				)
			)
		)
	)
)
